(kicad_pcb
	(version 20260206)
	(generator "pcbnew")
	(generator_version "10.0")
	(general
		(thickness 1.6)
		(legacy_teardrops no)
	)
	(paper "A4")
	(title_block
		(title "Wiwynn_Tioga_Pass_MB.brd")
		(comment 1 "Tioga Pass / footprints 1049-1056 of 4770")
	)
	(layers
		(0 "F.Cu" signal "TOP")
		(4 "In1.Cu" signal "L2GND")
		(6 "In2.Cu" signal "L3")
		(8 "In3.Cu" signal "L4GND")
		(10 "In4.Cu" signal "L5")
		(12 "In5.Cu" signal "L6GND")
		(14 "In6.Cu" signal "L7VCC")
		(16 "In7.Cu" signal "L8VCC")
		(18 "In8.Cu" signal "L9GND")
		(20 "In9.Cu" signal "L10")
		(22 "In10.Cu" signal "L11GND")
		(24 "In11.Cu" signal "L12")
		(26 "In12.Cu" signal "L13GND")
		(2 "B.Cu" signal "BOTTOM")
		(9 "F.Adhes" user "F.Adhesive")
		(11 "B.Adhes" user "B.Adhesive")
		(13 "F.Paste" user "Package Geometry/Pastemask Top")
		(15 "B.Paste" user "Package Geometry/Pastemask Bottom")
		(5 "F.SilkS" user "Ref Des/Silkscreen Top")
		(7 "B.SilkS" user "Ref Des/Silkscreen Bottom")
		(1 "F.Mask" user "Board Geometry/Soldermask Top")
		(3 "B.Mask" user "Board Geometry/Soldermask Bottom")
		(17 "Dwgs.User" user "User.Drawings")
		(19 "Cmts.User" user "User.Comments")
		(21 "Eco1.User" user "User.Eco1")
		(23 "Eco2.User" user "User.Eco2")
		(25 "Edge.Cuts" user "Board Geometry/Outline")
		(27 "Margin" user)
		(31 "F.CrtYd" user "Package Geometry/Place Bound Top")
		(29 "B.CrtYd" user "Package Geometry/Place Bound Bottom")
		(35 "F.Fab" user "Ref Des/Assembly Top")
		(33 "B.Fab" user "Ref Des/Assembly Bottom")
	)
	(footprint ""
		(layer "F.Cu")
		(at 482.67366 -30.29712 90)
		(property "Reference" "R8F29"
			(at 0 0 90)
			(layer "F.SilkS")
			(hide yes)
			(effects
				(font
					(size 1.27 1.27)
				)
			)
		)
		(property "Value" ""
			(at 0 0 90)
			(layer "F.Fab")
			(effects
				(font
					(size 1.27 1.27)
				)
			)
		)
		(duplicate_pad_numbers_are_jumpers no)
		(fp_poly
			(pts
				(xy -0.2794 -0.1016) (xy 0.2794 -0.1016) (xy 0.2794 0.9906) (xy -0.2794 0.9906)
			)
			(stroke
				(width 0)
				(type default)
			)
			(fill no)
			(layer "F.CrtYd")
		)
		(fp_line
			(start 0.2794 -0.1016)
			(end -0.2794 -0.1016)
			(stroke
				(width 0.1)
				(type default)
			)
			(layer "F.Fab")
		)
		(fp_line
			(start -0.2794 -0.1016)
			(end -0.2794 0.9906)
			(stroke
				(width 0.1)
				(type default)
			)
			(layer "F.Fab")
		)
		(fp_line
			(start 0.2794 0.9906)
			(end 0.2794 -0.1016)
			(stroke
				(width 0.1)
				(type default)
			)
			(layer "F.Fab")
		)
		(fp_line
			(start -0.2794 0.9906)
			(end 0.2794 0.9906)
			(stroke
				(width 0.1)
				(type default)
			)
			(layer "F.Fab")
		)
		(pad "1" smd rect
			(at 0 0 90)
			(size 0.508 0.508)
			(layers "F.Cu" "F.Mask" "F.Paste")
			(net "CLK_25M_BMC_R")
		)
		(pad "2" smd rect
			(at 0 0.889 90)
			(size 0.508 0.508)
			(layers "F.Cu" "F.Mask" "F.Paste")
			(net "CLK_25M_BMC")
		)
		(zone
			(layer "F.Cu")
			(hatch none 0.5)
			(connect_pads
				(clearance 0)
			)
			(min_thickness 0.25)
			(keepout
				(tracks allowed)
				(vias not_allowed)
				(pads allowed)
				(copperpour not_allowed)
				(footprints allowed)
			)
			(placement
				(enabled no)
				(sheetname "")
			)
			(fill
				(thermal_gap 0.5)
				(thermal_bridge_width 0.5)
				(island_removal_mode 0)
			)
			(polygon
				(pts
					(xy 482.92766 -30.04312) (xy 482.92766 -30.55112) (xy 483.30866 -30.55112) (xy 483.30866 -30.04312)
				)
			)
		)
		(zone
			(layer "F.Cu")
			(hatch none 0.5)
			(connect_pads
				(clearance 0)
			)
			(min_thickness 0.25)
			(keepout
				(tracks not_allowed)
				(vias allowed)
				(pads allowed)
				(copperpour not_allowed)
				(footprints allowed)
			)
			(placement
				(enabled no)
				(sheetname "")
			)
			(fill
				(thermal_gap 0.5)
				(thermal_bridge_width 0.5)
				(island_removal_mode 0)
			)
			(polygon
				(pts
					(xy 483.30866 -30.04312) (xy 483.30866 -30.55112) (xy 482.92766 -30.55112) (xy 482.92766 -30.04312)
				)
			)
		)
	)
	(footprint ""
		(layer "F.Cu")
		(at 22.225 -75.438 90)
		(property "Reference" "R1D34"
			(at 0 0 90)
			(layer "F.SilkS")
			(hide yes)
			(effects
				(font
					(size 1.27 1.27)
				)
			)
		)
		(property "Value" ""
			(at 0 0 90)
			(layer "F.Fab")
			(effects
				(font
					(size 1.27 1.27)
				)
			)
		)
		(duplicate_pad_numbers_are_jumpers no)
		(fp_poly
			(pts
				(xy -0.2794 -0.1016) (xy 0.2794 -0.1016) (xy 0.2794 0.9906) (xy -0.2794 0.9906)
			)
			(stroke
				(width 0)
				(type default)
			)
			(fill no)
			(layer "F.CrtYd")
		)
		(fp_line
			(start 0.2794 -0.1016)
			(end -0.2794 -0.1016)
			(stroke
				(width 0.1)
				(type default)
			)
			(layer "F.Fab")
		)
		(fp_line
			(start -0.2794 -0.1016)
			(end -0.2794 0.9906)
			(stroke
				(width 0.1)
				(type default)
			)
			(layer "F.Fab")
		)
		(fp_line
			(start 0.2794 0.9906)
			(end 0.2794 -0.1016)
			(stroke
				(width 0.1)
				(type default)
			)
			(layer "F.Fab")
		)
		(fp_line
			(start -0.2794 0.9906)
			(end 0.2794 0.9906)
			(stroke
				(width 0.1)
				(type default)
			)
			(layer "F.Fab")
		)
		(pad "1" smd rect
			(at 0 0 90)
			(size 0.508 0.508)
			(layers "F.Cu" "F.Mask" "F.Paste")
			(net "A_HSC_ISTART")
		)
		(pad "2" smd rect
			(at 0 0.889 90)
			(size 0.508 0.508)
			(layers "F.Cu" "F.Mask" "F.Paste")
			(net "AGND_HSC")
		)
		(zone
			(layer "F.Cu")
			(hatch none 0.5)
			(connect_pads
				(clearance 0)
			)
			(min_thickness 0.25)
			(keepout
				(tracks allowed)
				(vias not_allowed)
				(pads allowed)
				(copperpour not_allowed)
				(footprints allowed)
			)
			(placement
				(enabled no)
				(sheetname "")
			)
			(fill
				(thermal_gap 0.5)
				(thermal_bridge_width 0.5)
				(island_removal_mode 0)
			)
			(polygon
				(pts
					(xy 22.479 -75.184) (xy 22.479 -75.692) (xy 22.86 -75.692) (xy 22.86 -75.184)
				)
			)
		)
		(zone
			(layer "F.Cu")
			(hatch none 0.5)
			(connect_pads
				(clearance 0)
			)
			(min_thickness 0.25)
			(keepout
				(tracks not_allowed)
				(vias allowed)
				(pads allowed)
				(copperpour not_allowed)
				(footprints allowed)
			)
			(placement
				(enabled no)
				(sheetname "")
			)
			(fill
				(thermal_gap 0.5)
				(thermal_bridge_width 0.5)
				(island_removal_mode 0)
			)
			(polygon
				(pts
					(xy 22.86 -75.184) (xy 22.86 -75.692) (xy 22.479 -75.692) (xy 22.479 -75.184)
				)
			)
		)
	)
	(footprint ""
		(layer "F.Cu")
		(at 13.843 -89.281 90)
		(property "Reference" "R1C28"
			(at 0 0 90)
			(layer "F.SilkS")
			(hide yes)
			(effects
				(font
					(size 1.27 1.27)
				)
			)
		)
		(property "Value" ""
			(at 0 0 90)
			(layer "F.Fab")
			(effects
				(font
					(size 1.27 1.27)
				)
			)
		)
		(duplicate_pad_numbers_are_jumpers no)
		(fp_rect
			(start -0.2794 -0.1016)
			(end 0.2794 0.9906)
			(stroke
				(width 0)
				(type default)
			)
			(fill no)
			(layer "F.CrtYd")
		)
		(fp_line
			(start 0.2794 -0.1016)
			(end -0.2794 -0.1016)
			(stroke
				(width 0.1)
				(type default)
			)
			(layer "F.Fab")
		)
		(fp_line
			(start -0.2794 -0.1016)
			(end -0.2794 0.9906)
			(stroke
				(width 0.1)
				(type default)
			)
			(layer "F.Fab")
		)
		(fp_line
			(start 0.2794 0.9906)
			(end 0.2794 -0.1016)
			(stroke
				(width 0.1)
				(type default)
			)
			(layer "F.Fab")
		)
		(fp_line
			(start -0.2794 0.9906)
			(end 0.2794 0.9906)
			(stroke
				(width 0.1)
				(type default)
			)
			(layer "F.Fab")
		)
		(pad "1" smd rect
			(at 0 0 90)
			(size 0.508 0.508)
			(layers "F.Cu" "F.Mask" "F.Paste")
			(net "P3V3_STBY")
		)
		(pad "2" smd rect
			(at 0 0.889 90)
			(size 0.508 0.508)
			(layers "F.Cu" "F.Mask" "F.Paste")
			(net "VR_VRRDY_PVCCIN_CPU1")
		)
		(zone
			(layer "F.Cu")
			(hatch none 0.5)
			(connect_pads
				(clearance 0)
			)
			(min_thickness 0.25)
			(keepout
				(tracks not_allowed)
				(vias allowed)
				(pads allowed)
				(copperpour not_allowed)
				(footprints allowed)
			)
			(placement
				(enabled no)
				(sheetname "")
			)
			(fill
				(thermal_gap 0.5)
				(thermal_bridge_width 0.5)
				(island_removal_mode 0)
			)
			(polygon
				(pts
					(xy 14.097 -89.027) (xy 14.478 -89.027) (xy 14.478 -89.535) (xy 14.097 -89.535)
				)
			)
		)
		(zone
			(layer "F.Cu")
			(hatch none 0.5)
			(connect_pads
				(clearance 0)
			)
			(min_thickness 0.25)
			(keepout
				(tracks allowed)
				(vias not_allowed)
				(pads allowed)
				(copperpour not_allowed)
				(footprints allowed)
			)
			(placement
				(enabled no)
				(sheetname "")
			)
			(fill
				(thermal_gap 0.5)
				(thermal_bridge_width 0.5)
				(island_removal_mode 0)
			)
			(polygon
				(pts
					(xy 14.097 -89.027) (xy 14.478 -89.027) (xy 14.478 -89.535) (xy 14.097 -89.535)
				)
			)
		)
	)
	(footprint ""
		(layer "F.Cu")
		(at 112.062768 -79.6036 180)
		(property "Reference" "C3D7"
			(at 0 0 180)
			(layer "F.SilkS")
			(hide yes)
			(effects
				(font
					(size 1.27 1.27)
				)
			)
		)
		(property "Value" ""
			(at 0 0 180)
			(layer "F.Fab")
			(effects
				(font
					(size 1.27 1.27)
				)
			)
		)
		(duplicate_pad_numbers_are_jumpers no)
		(fp_poly
			(pts
				(xy -0.4953 -0.2032) (xy 0.4953 -0.2032) (xy 0.4953 1.6002) (xy -0.4953 1.6002)
			)
			(stroke
				(width 0)
				(type default)
			)
			(fill no)
			(layer "F.CrtYd")
		)
		(fp_line
			(start 0.4953 1.6002)
			(end -0.4953 1.6002)
			(stroke
				(width 0.1)
				(type default)
			)
			(layer "F.Fab")
		)
		(fp_line
			(start 0.4953 -0.2032)
			(end 0.4953 1.6002)
			(stroke
				(width 0.1)
				(type default)
			)
			(layer "F.Fab")
		)
		(fp_line
			(start -0.4953 1.6002)
			(end -0.4953 -0.2032)
			(stroke
				(width 0.1)
				(type default)
			)
			(layer "F.Fab")
		)
		(fp_line
			(start -0.4953 -0.2032)
			(end 0.4953 -0.2032)
			(stroke
				(width 0.1)
				(type default)
			)
			(layer "F.Fab")
		)
		(pad "1" smd rect
			(at 0 0 180)
			(size 0.762 0.889)
			(layers "F.Cu" "F.Mask" "F.Paste")
			(net "PVCCMCP_CPU1")
		)
		(pad "2" smd rect
			(at 0 1.397 180)
			(size 0.762 0.889)
			(layers "F.Cu" "F.Mask" "F.Paste")
			(net "GND")
		)
		(zone
			(layer "F.Cu")
			(hatch none 0.5)
			(connect_pads
				(clearance 0)
			)
			(min_thickness 0.25)
			(keepout
				(tracks not_allowed)
				(vias allowed)
				(pads allowed)
				(copperpour not_allowed)
				(footprints allowed)
			)
			(placement
				(enabled no)
				(sheetname "")
			)
			(fill
				(thermal_gap 0.5)
				(thermal_bridge_width 0.5)
				(island_removal_mode 0)
			)
			(polygon
				(pts
					(xy 112.443768 -80.0481) (xy 111.681768 -80.0481) (xy 111.681768 -80.5561) (xy 112.443768 -80.5561)
				)
			)
		)
	)
	(footprint ""
		(layer "F.Cu")
		(at 261.747 -129.859024)
		(property "Reference" "C5B1"
			(at 0 0 0)
			(layer "F.SilkS")
			(hide yes)
			(effects
				(font
					(size 1.27 1.27)
				)
			)
		)
		(property "Value" ""
			(at 0 0 0)
			(layer "F.Fab")
			(effects
				(font
					(size 1.27 1.27)
				)
			)
		)
		(duplicate_pad_numbers_are_jumpers no)
		(fp_rect
			(start -0.500126 1.598422)
			(end 0.500126 -0.201422)
			(stroke
				(width 0)
				(type default)
			)
			(fill no)
			(layer "F.CrtYd")
		)
		(fp_line
			(start -0.500126 -0.201422)
			(end 0.500126 -0.201422)
			(stroke
				(width 0.1)
				(type default)
			)
			(layer "F.Fab")
		)
		(fp_line
			(start -0.500126 1.598422)
			(end -0.500126 -0.201422)
			(stroke
				(width 0.1)
				(type default)
			)
			(layer "F.Fab")
		)
		(fp_line
			(start 0.500126 -0.201422)
			(end 0.500126 1.598422)
			(stroke
				(width 0.1)
				(type default)
			)
			(layer "F.Fab")
		)
		(fp_line
			(start 0.500126 1.598422)
			(end -0.500126 1.598422)
			(stroke
				(width 0.1)
				(type default)
			)
			(layer "F.Fab")
		)
		(pad "1" smd rect
			(at 0 0 270)
			(size 0.889 0.9906)
			(layers "F.Cu" "F.Mask" "F.Paste")
			(net "PVDDQ_DEF")
		)
		(pad "2" smd rect
			(at 0 1.397 270)
			(size 0.889 0.9906)
			(layers "F.Cu" "F.Mask" "F.Paste")
			(net "GND")
		)
		(zone
			(layer "F.Cu")
			(hatch none 0.5)
			(connect_pads
				(clearance 0)
			)
			(min_thickness 0.25)
			(keepout
				(tracks allowed)
				(vias not_allowed)
				(pads allowed)
				(copperpour not_allowed)
				(footprints allowed)
			)
			(placement
				(enabled no)
				(sheetname "")
			)
			(fill
				(thermal_gap 0.5)
				(thermal_bridge_width 0.5)
				(island_removal_mode 0)
			)
			(polygon
				(pts
					(xy 261.2517 -128.906524) (xy 262.2423 -128.906524) (xy 262.2423 -129.414524) (xy 261.2517 -129.414524)
				)
			)
		)
		(zone
			(layer "F.Cu")
			(hatch none 0.5)
			(connect_pads
				(clearance 0)
			)
			(min_thickness 0.25)
			(keepout
				(tracks not_allowed)
				(vias allowed)
				(pads allowed)
				(copperpour not_allowed)
				(footprints allowed)
			)
			(placement
				(enabled no)
				(sheetname "")
			)
			(fill
				(thermal_gap 0.5)
				(thermal_bridge_width 0.5)
				(island_removal_mode 0)
			)
			(polygon
				(pts
					(xy 261.2517 -128.906524) (xy 262.2423 -128.906524) (xy 262.2423 -129.414524) (xy 261.2517 -129.414524)
				)
			)
		)
	)
	(footprint ""
		(layer "F.Cu")
		(at 399.932144 -40.404542 -90)
		(property "Reference" "C9W7"
			(at -0.8382 -0.67818 270)
			(unlocked yes)
			(layer "F.SilkS")
			(effects
				(font
					(size 0.4064 0.254)
					(thickness 0.1524)
				)
				(justify left)
			)
		)
		(property "Value" ""
			(at 0 0 270)
			(layer "F.Fab")
			(effects
				(font
					(size 1.27 1.27)
				)
			)
		)
		(duplicate_pad_numbers_are_jumpers no)
		(fp_poly
			(pts
				(xy 0.3048 -0.1016) (xy 0.3048 0.9906) (xy -0.3048 0.9906) (xy -0.3048 -0.1016)
			)
			(stroke
				(width 0)
				(type default)
			)
			(fill no)
			(layer "F.CrtYd")
		)
		(fp_line
			(start -0.3048 0.9906)
			(end 0.3048 0.9906)
			(stroke
				(width 0.1)
				(type default)
			)
			(layer "F.Fab")
		)
		(fp_line
			(start 0.3048 0.9906)
			(end 0.3048 -0.1016)
			(stroke
				(width 0.1)
				(type default)
			)
			(layer "F.Fab")
		)
		(fp_line
			(start -0.3048 -0.1016)
			(end -0.3048 0.9906)
			(stroke
				(width 0.1)
				(type default)
			)
			(layer "F.Fab")
		)
		(fp_line
			(start 0.3048 -0.1016)
			(end -0.3048 -0.1016)
			(stroke
				(width 0.1)
				(type default)
			)
			(layer "F.Fab")
		)
		(pad "1" smd rect
			(at 0 0 270)
			(size 0.508 0.508)
			(layers "F.Cu" "F.Mask" "F.Paste")
			(net "P3V3_STBY")
		)
		(pad "2" smd rect
			(at 0 0.889 270)
			(size 0.508 0.508)
			(layers "F.Cu" "F.Mask" "F.Paste")
			(net "GND")
		)
		(zone
			(layer "F.Cu")
			(hatch none 0.5)
			(connect_pads
				(clearance 0)
			)
			(min_thickness 0.25)
			(keepout
				(tracks not_allowed)
				(vias allowed)
				(pads allowed)
				(copperpour not_allowed)
				(footprints allowed)
			)
			(placement
				(enabled no)
				(sheetname "")
			)
			(fill
				(thermal_gap 0.5)
				(thermal_bridge_width 0.5)
				(island_removal_mode 0)
			)
			(polygon
				(pts
					(xy 399.297144 -40.658542) (xy 399.297144 -40.150542) (xy 399.678144 -40.150542) (xy 399.678144 -40.658542)
				)
			)
		)
		(zone
			(layer "F.Cu")
			(hatch none 0.5)
			(connect_pads
				(clearance 0)
			)
			(min_thickness 0.25)
			(keepout
				(tracks allowed)
				(vias not_allowed)
				(pads allowed)
				(copperpour not_allowed)
				(footprints allowed)
			)
			(placement
				(enabled no)
				(sheetname "")
			)
			(fill
				(thermal_gap 0.5)
				(thermal_bridge_width 0.5)
				(island_removal_mode 0)
			)
			(polygon
				(pts
					(xy 399.678144 -40.658542) (xy 399.678144 -40.150542) (xy 399.297144 -40.150542) (xy 399.297144 -40.658542)
				)
			)
		)
	)
	(footprint ""
		(layer "F.Cu")
		(at 155.194 -27.9908 180)
		(property "Reference" "R3F3"
			(at 0 0 180)
			(layer "F.SilkS")
			(hide yes)
			(effects
				(font
					(size 1.27 1.27)
				)
			)
		)
		(property "Value" ""
			(at 0 0 180)
			(layer "F.Fab")
			(effects
				(font
					(size 1.27 1.27)
				)
			)
		)
		(duplicate_pad_numbers_are_jumpers no)
		(fp_poly
			(pts
				(xy -0.2794 -0.1016) (xy 0.2794 -0.1016) (xy 0.2794 0.9906) (xy -0.2794 0.9906)
			)
			(stroke
				(width 0)
				(type default)
			)
			(fill no)
			(layer "F.CrtYd")
		)
		(fp_line
			(start 0.2794 0.9906)
			(end 0.2794 -0.1016)
			(stroke
				(width 0.1)
				(type default)
			)
			(layer "F.Fab")
		)
		(fp_line
			(start 0.2794 -0.1016)
			(end -0.2794 -0.1016)
			(stroke
				(width 0.1)
				(type default)
			)
			(layer "F.Fab")
		)
		(fp_line
			(start -0.2794 0.9906)
			(end 0.2794 0.9906)
			(stroke
				(width 0.1)
				(type default)
			)
			(layer "F.Fab")
		)
		(fp_line
			(start -0.2794 -0.1016)
			(end -0.2794 0.9906)
			(stroke
				(width 0.1)
				(type default)
			)
			(layer "F.Fab")
		)
		(pad "1" smd rect
			(at 0 0 180)
			(size 0.508 0.508)
			(layers "F.Cu" "F.Mask" "F.Paste")
			(net "CLK_322M_156M_CPU1_OSC_VRM_DP")
		)
		(pad "2" smd rect
			(at 0 0.889 180)
			(size 0.508 0.508)
			(layers "F.Cu" "F.Mask" "F.Paste")
			(net "CLK_156M_OSC_CPU1_HFI_DP")
		)
		(zone
			(layer "F.Cu")
			(hatch none 0.5)
			(connect_pads
				(clearance 0)
			)
			(min_thickness 0.25)
			(keepout
				(tracks not_allowed)
				(vias allowed)
				(pads allowed)
				(copperpour not_allowed)
				(footprints allowed)
			)
			(placement
				(enabled no)
				(sheetname "")
			)
			(fill
				(thermal_gap 0.5)
				(thermal_bridge_width 0.5)
				(island_removal_mode 0)
			)
			(polygon
				(pts
					(xy 155.448 -28.6258) (xy 154.94 -28.6258) (xy 154.94 -28.2448) (xy 155.448 -28.2448)
				)
			)
		)
		(zone
			(layer "F.Cu")
			(hatch none 0.5)
			(connect_pads
				(clearance 0)
			)
			(min_thickness 0.25)
			(keepout
				(tracks allowed)
				(vias not_allowed)
				(pads allowed)
				(copperpour not_allowed)
				(footprints allowed)
			)
			(placement
				(enabled no)
				(sheetname "")
			)
			(fill
				(thermal_gap 0.5)
				(thermal_bridge_width 0.5)
				(island_removal_mode 0)
			)
			(polygon
				(pts
					(xy 155.448 -28.2448) (xy 154.94 -28.2448) (xy 154.94 -28.6258) (xy 155.448 -28.6258)
				)
			)
		)
	)
	(footprint ""
		(layer "F.Cu")
		(at 394.5763 -147.0152 90)
		(property "Reference" "C7B19"
			(at 0 0 90)
			(layer "F.SilkS")
			(hide yes)
			(effects
				(font
					(size 1.27 1.27)
				)
			)
		)
		(property "Value" ""
			(at 0 0 90)
			(layer "F.Fab")
			(effects
				(font
					(size 1.27 1.27)
				)
			)
		)
		(duplicate_pad_numbers_are_jumpers no)
		(fp_rect
			(start -0.4953 -0.2032)
			(end 0.4953 1.6002)
			(stroke
				(width 0)
				(type default)
			)
			(fill no)
			(layer "F.CrtYd")
		)
		(fp_line
			(start 0.4953 -0.2032)
			(end 0.4953 1.6002)
			(stroke
				(width 0.1)
				(type default)
			)
			(layer "F.Fab")
		)
		(fp_line
			(start -0.4953 -0.2032)
			(end 0.4953 -0.2032)
			(stroke
				(width 0.1)
				(type default)
			)
			(layer "F.Fab")
		)
		(fp_line
			(start 0.4953 1.6002)
			(end -0.4953 1.6002)
			(stroke
				(width 0.1)
				(type default)
			)
			(layer "F.Fab")
		)
		(fp_line
			(start -0.4953 1.6002)
			(end -0.4953 -0.2032)
			(stroke
				(width 0.1)
				(type default)
			)
			(layer "F.Fab")
		)
		(pad "1" smd rect
			(at 0 0 90)
			(size 0.762 0.889)
			(layers "F.Cu" "F.Mask" "F.Paste")
			(net "P1V05_PCH_STBY")
		)
		(pad "2" smd rect
			(at 0 1.397 90)
			(size 0.762 0.889)
			(layers "F.Cu" "F.Mask" "F.Paste")
			(net "GND")
		)
		(zone
			(layer "F.Cu")
			(hatch none 0.5)
			(connect_pads
				(clearance 0)
			)
			(min_thickness 0.25)
			(keepout
				(tracks not_allowed)
				(vias allowed)
				(pads allowed)
				(copperpour not_allowed)
				(footprints allowed)
			)
			(placement
				(enabled no)
				(sheetname "")
			)
			(fill
				(thermal_gap 0.5)
				(thermal_bridge_width 0.5)
				(island_removal_mode 0)
			)
			(polygon
				(pts
					(xy 395.0208 -146.6342) (xy 395.5288 -146.6342) (xy 395.5288 -147.3962) (xy 395.0208 -147.3962)
				)
			)
		)
	)
)
